(kicad_pcb
	(version 20260206)
	(generator "pcbnew")
	(generator_version "10.0")
	(general
		(thickness 1.6)
		(legacy_teardrops no)
	)
	(paper "A4")
	(title_block
		(title "03242023_DA0F0TMBIJ0_F0T_Motherboard_J_brd_V01_OCP.brd")
		(comment 1 "Grand Teton / footprints 3040-3046 of 6105")
	)
	(layers
		(0 "F.Cu" signal "TOP")
		(4 "In1.Cu" signal "GND")
		(6 "In2.Cu" signal "IN1")
		(8 "In3.Cu" signal "GND1")
		(10 "In4.Cu" signal "IN2")
		(12 "In5.Cu" signal "GND2")
		(14 "In6.Cu" signal "IN3")
		(16 "In7.Cu" signal "GND3")
		(18 "In8.Cu" signal "VCC")
		(20 "In9.Cu" signal "VCC1")
		(22 "In10.Cu" signal "GND4")
		(24 "In11.Cu" signal "IN4")
		(26 "In12.Cu" signal "GND5")
		(28 "In13.Cu" signal "IN5")
		(30 "In14.Cu" signal "GND6")
		(32 "In15.Cu" signal "IN6")
		(34 "In16.Cu" signal "GND7")
		(2 "B.Cu" signal "BOTTOM")
		(9 "F.Adhes" user "F.Adhesive")
		(11 "B.Adhes" user "B.Adhesive")
		(13 "F.Paste" user "Package Geometry/Pastemask Top")
		(15 "B.Paste" user "Package Geometry/Pastemask Bottom")
		(5 "F.SilkS" user "Ref Des/Silkscreen Top")
		(7 "B.SilkS" user "Ref Des/Silkscreen Bottom")
		(1 "F.Mask" user "Board Geometry/Soldermask Top")
		(3 "B.Mask" user "Board Geometry/Soldermask Bottom")
		(17 "Dwgs.User" user "User.Drawings")
		(19 "Cmts.User" user "User.Comments")
		(21 "Eco1.User" user "User.Eco1")
		(23 "Eco2.User" user "User.Eco2")
		(25 "Edge.Cuts" user "Board Geometry/Outline")
		(27 "Margin" user)
		(31 "F.CrtYd" user "Package Geometry/Place Bound Top")
		(29 "B.CrtYd" user "Package Geometry/Place Bound Bottom")
		(35 "F.Fab" user "Ref Des/Assembly Top")
		(33 "B.Fab" user "Ref Des/Assembly Bottom")
	)
	(footprint ""
		(layer "F.Cu")
		(at 32.761428 -99.586034 180)
		(property "Reference" "C2176"
			(at 0 0 180)
			(layer "F.SilkS")
			(hide yes)
			(effects
				(font
					(size 1.27 1.27)
				)
			)
		)
		(property "Value" ""
			(at 0 0 180)
			(layer "F.Fab")
			(effects
				(font
					(size 1.27 1.27)
				)
			)
		)
		(duplicate_pad_numbers_are_jumpers no)
		(fp_line
			(start 0.7874 0.4064)
			(end -0.7874 0.4064)
			(stroke
				(width 0.1524)
				(type default)
			)
			(layer "F.SilkS")
		)
		(fp_line
			(start 0.7874 -0.4064)
			(end 0.7874 0.4064)
			(stroke
				(width 0.1524)
				(type default)
			)
			(layer "F.SilkS")
		)
		(fp_line
			(start -0.7874 0.4064)
			(end -0.7874 -0.4064)
			(stroke
				(width 0.1524)
				(type default)
			)
			(layer "F.SilkS")
		)
		(fp_line
			(start -0.7874 -0.4064)
			(end 0.7874 -0.4064)
			(stroke
				(width 0.1524)
				(type default)
			)
			(layer "F.SilkS")
		)
		(fp_line
			(start 0.67945 0.3048)
			(end 0.120396 0.3048)
			(stroke
				(width 0.1)
				(type default)
			)
			(layer "F.Fab")
		)
		(fp_line
			(start 0.67945 -0.3048)
			(end 0.67945 0.3048)
			(stroke
				(width 0.1)
				(type default)
			)
			(layer "F.Fab")
		)
		(fp_line
			(start 0.12065 -0.2794)
			(end 0.12065 -0.3048)
			(stroke
				(width 0.1)
				(type default)
			)
			(layer "F.Fab")
		)
		(fp_line
			(start 0.12065 -0.3048)
			(end 0.67945 -0.3048)
			(stroke
				(width 0.1)
				(type default)
			)
			(layer "F.Fab")
		)
		(fp_line
			(start 0.120396 0.3048)
			(end 0.120396 0.2794)
			(stroke
				(width 0.1)
				(type default)
			)
			(layer "F.Fab")
		)
		(fp_line
			(start 0.120396 0.2794)
			(end -0.12065 0.2794)
			(stroke
				(width 0.1)
				(type default)
			)
			(layer "F.Fab")
		)
		(fp_line
			(start -0.12065 0.3048)
			(end -0.67945 0.3048)
			(stroke
				(width 0.1)
				(type default)
			)
			(layer "F.Fab")
		)
		(fp_line
			(start -0.12065 0.2794)
			(end -0.12065 0.3048)
			(stroke
				(width 0.1)
				(type default)
			)
			(layer "F.Fab")
		)
		(fp_line
			(start -0.12065 -0.2794)
			(end 0.12065 -0.2794)
			(stroke
				(width 0.1)
				(type default)
			)
			(layer "F.Fab")
		)
		(fp_line
			(start -0.12065 -0.305054)
			(end -0.12065 -0.2794)
			(stroke
				(width 0.1)
				(type default)
			)
			(layer "F.Fab")
		)
		(fp_line
			(start -0.67945 0.3048)
			(end -0.67945 -0.305054)
			(stroke
				(width 0.1)
				(type default)
			)
			(layer "F.Fab")
		)
		(fp_line
			(start -0.67945 -0.305054)
			(end -0.12065 -0.305054)
			(stroke
				(width 0.1)
				(type default)
			)
			(layer "F.Fab")
		)
		(pad "1" smd circle
			(at -0.40005 0 180)
			(size 0 0)
			(layers "F.Cu" "F.Mask" "F.Paste")
			(net "P12V_OCP_SFF_ISENSE_MAM")
		)
		(pad "2" smd circle
			(at 0.40005 0 180)
			(size 0 0)
			(layers "F.Cu" "F.Mask" "F.Paste")
			(net "GND")
		)
	)
	(footprint ""
		(layer "F.Cu")
		(at 425.71416 -143.675608 90)
		(property "Reference" "PR4222"
			(at 0 0 90)
			(layer "F.SilkS")
			(hide yes)
			(effects
				(font
					(size 1.27 1.27)
				)
			)
		)
		(property "Value" ""
			(at 0 0 90)
			(layer "F.Fab")
			(effects
				(font
					(size 1.27 1.27)
				)
			)
		)
		(duplicate_pad_numbers_are_jumpers no)
		(fp_line
			(start 0.7874 -0.4064)
			(end 0.7874 0.4064)
			(stroke
				(width 0.1524)
				(type default)
			)
			(layer "F.SilkS")
		)
		(fp_line
			(start -0.7874 -0.4064)
			(end 0.7874 -0.4064)
			(stroke
				(width 0.1524)
				(type default)
			)
			(layer "F.SilkS")
		)
		(fp_line
			(start 0.7874 0.4064)
			(end -0.7874 0.4064)
			(stroke
				(width 0.1524)
				(type default)
			)
			(layer "F.SilkS")
		)
		(fp_line
			(start -0.7874 0.4064)
			(end -0.7874 -0.4064)
			(stroke
				(width 0.1524)
				(type default)
			)
			(layer "F.SilkS")
		)
		(fp_line
			(start -0.12065 -0.305054)
			(end -0.12065 -0.2794)
			(stroke
				(width 0.1)
				(type default)
			)
			(layer "F.Fab")
		)
		(fp_line
			(start -0.67945 -0.305054)
			(end -0.12065 -0.305054)
			(stroke
				(width 0.1)
				(type default)
			)
			(layer "F.Fab")
		)
		(fp_line
			(start 0.67945 -0.3048)
			(end 0.67945 0.3048)
			(stroke
				(width 0.1)
				(type default)
			)
			(layer "F.Fab")
		)
		(fp_line
			(start 0.12065 -0.3048)
			(end 0.67945 -0.3048)
			(stroke
				(width 0.1)
				(type default)
			)
			(layer "F.Fab")
		)
		(fp_line
			(start 0.12065 -0.2794)
			(end 0.12065 -0.3048)
			(stroke
				(width 0.1)
				(type default)
			)
			(layer "F.Fab")
		)
		(fp_line
			(start -0.12065 -0.2794)
			(end 0.12065 -0.2794)
			(stroke
				(width 0.1)
				(type default)
			)
			(layer "F.Fab")
		)
		(fp_line
			(start 0.120396 0.2794)
			(end -0.12065 0.2794)
			(stroke
				(width 0.1)
				(type default)
			)
			(layer "F.Fab")
		)
		(fp_line
			(start -0.12065 0.2794)
			(end -0.12065 0.3048)
			(stroke
				(width 0.1)
				(type default)
			)
			(layer "F.Fab")
		)
		(fp_line
			(start 0.67945 0.3048)
			(end 0.120396 0.3048)
			(stroke
				(width 0.1)
				(type default)
			)
			(layer "F.Fab")
		)
		(fp_line
			(start 0.120396 0.3048)
			(end 0.120396 0.2794)
			(stroke
				(width 0.1)
				(type default)
			)
			(layer "F.Fab")
		)
		(fp_line
			(start -0.12065 0.3048)
			(end -0.67945 0.3048)
			(stroke
				(width 0.1)
				(type default)
			)
			(layer "F.Fab")
		)
		(fp_line
			(start -0.67945 0.3048)
			(end -0.67945 -0.305054)
			(stroke
				(width 0.1)
				(type default)
			)
			(layer "F.Fab")
		)
		(pad "1" smd circle
			(at -0.40005 0 90)
			(size 0 0)
			(layers "F.Cu" "F.Mask" "F.Paste")
			(net "NC_PVCCINFAON_CPU0_ACSP4")
		)
		(pad "2" smd circle
			(at 0.40005 0 90)
			(size 0 0)
			(layers "F.Cu" "F.Mask" "F.Paste")
			(net "GND")
		)
	)
	(footprint ""
		(layer "F.Cu")
		(at 4.699 -50.891948 180)
		(property "Reference" "R579"
			(at 0 0 180)
			(layer "F.SilkS")
			(hide yes)
			(effects
				(font
					(size 1.27 1.27)
				)
			)
		)
		(property "Value" ""
			(at 0 0 180)
			(layer "F.Fab")
			(effects
				(font
					(size 1.27 1.27)
				)
			)
		)
		(duplicate_pad_numbers_are_jumpers no)
		(fp_line
			(start 0.7874 0.4064)
			(end -0.7874 0.4064)
			(stroke
				(width 0.1524)
				(type default)
			)
			(layer "F.SilkS")
		)
		(fp_line
			(start 0.7874 -0.4064)
			(end 0.7874 0.4064)
			(stroke
				(width 0.1524)
				(type default)
			)
			(layer "F.SilkS")
		)
		(fp_line
			(start -0.7874 0.4064)
			(end -0.7874 -0.4064)
			(stroke
				(width 0.1524)
				(type default)
			)
			(layer "F.SilkS")
		)
		(fp_line
			(start -0.7874 -0.4064)
			(end 0.7874 -0.4064)
			(stroke
				(width 0.1524)
				(type default)
			)
			(layer "F.SilkS")
		)
		(fp_line
			(start 0.67945 0.3048)
			(end 0.120396 0.3048)
			(stroke
				(width 0.1)
				(type default)
			)
			(layer "F.Fab")
		)
		(fp_line
			(start 0.67945 -0.3048)
			(end 0.67945 0.3048)
			(stroke
				(width 0.1)
				(type default)
			)
			(layer "F.Fab")
		)
		(fp_line
			(start 0.12065 -0.2794)
			(end 0.12065 -0.3048)
			(stroke
				(width 0.1)
				(type default)
			)
			(layer "F.Fab")
		)
		(fp_line
			(start 0.12065 -0.3048)
			(end 0.67945 -0.3048)
			(stroke
				(width 0.1)
				(type default)
			)
			(layer "F.Fab")
		)
		(fp_line
			(start 0.120396 0.3048)
			(end 0.120396 0.2794)
			(stroke
				(width 0.1)
				(type default)
			)
			(layer "F.Fab")
		)
		(fp_line
			(start 0.120396 0.2794)
			(end -0.12065 0.2794)
			(stroke
				(width 0.1)
				(type default)
			)
			(layer "F.Fab")
		)
		(fp_line
			(start -0.12065 0.3048)
			(end -0.67945 0.3048)
			(stroke
				(width 0.1)
				(type default)
			)
			(layer "F.Fab")
		)
		(fp_line
			(start -0.12065 0.2794)
			(end -0.12065 0.3048)
			(stroke
				(width 0.1)
				(type default)
			)
			(layer "F.Fab")
		)
		(fp_line
			(start -0.12065 -0.2794)
			(end 0.12065 -0.2794)
			(stroke
				(width 0.1)
				(type default)
			)
			(layer "F.Fab")
		)
		(fp_line
			(start -0.12065 -0.305054)
			(end -0.12065 -0.2794)
			(stroke
				(width 0.1)
				(type default)
			)
			(layer "F.Fab")
		)
		(fp_line
			(start -0.67945 0.3048)
			(end -0.67945 -0.305054)
			(stroke
				(width 0.1)
				(type default)
			)
			(layer "F.Fab")
		)
		(fp_line
			(start -0.67945 -0.305054)
			(end -0.12065 -0.305054)
			(stroke
				(width 0.1)
				(type default)
			)
			(layer "F.Fab")
		)
		(pad "1" smd circle
			(at -0.40005 0 180)
			(size 0 0)
			(layers "F.Cu" "F.Mask" "F.Paste")
			(net "SMB_HOST_3V3AUX_SCL_R5")
		)
		(pad "2" smd circle
			(at 0.40005 0 180)
			(size 0 0)
			(layers "F.Cu" "F.Mask" "F.Paste")
			(net "SMB_HOST_BMC_3V3AUX_SCL")
		)
	)
	(footprint ""
		(layer "F.Cu")
		(at 158.234634 -408.517344 -90)
		(property "Reference" "C1540"
			(at 0 0 270)
			(layer "F.SilkS")
			(hide yes)
			(effects
				(font
					(size 1.27 1.27)
				)
			)
		)
		(property "Value" ""
			(at 0 0 270)
			(layer "F.Fab")
			(effects
				(font
					(size 1.27 1.27)
				)
			)
		)
		(duplicate_pad_numbers_are_jumpers no)
		(fp_line
			(start -0.299974 0.150114)
			(end -0.299974 -0.150114)
			(stroke
				(width 0.1)
				(type default)
			)
			(layer "F.Fab")
		)
		(fp_line
			(start 0.299974 0.150114)
			(end -0.299974 0.150114)
			(stroke
				(width 0.1)
				(type default)
			)
			(layer "F.Fab")
		)
		(fp_line
			(start -0.299974 -0.150114)
			(end 0.299974 -0.150114)
			(stroke
				(width 0.1)
				(type default)
			)
			(layer "F.Fab")
		)
		(fp_line
			(start 0.299974 -0.150114)
			(end 0.299974 0.150114)
			(stroke
				(width 0.1)
				(type default)
			)
			(layer "F.Fab")
		)
		(pad "1" smd rect
			(at -0.2667 0 270)
			(size 0.3048 0.381)
			(layers "F.Cu" "F.Mask" "F.Paste")
			(net "P5E_CPU1_PE3_TX_C_DN<3>")
		)
		(pad "2" smd rect
			(at 0.2667 0 270)
			(size 0.3048 0.381)
			(layers "F.Cu" "F.Mask" "F.Paste")
			(net "P5E_CPU1_PE3_TX_DN<3>")
		)
	)
	(footprint ""
		(layer "F.Cu")
		(at 83.730592 -65.068958 -90)
		(property "Reference" "R3070"
			(at 0 0 270)
			(layer "F.SilkS")
			(hide yes)
			(effects
				(font
					(size 1.27 1.27)
				)
			)
		)
		(property "Value" ""
			(at 0 0 270)
			(layer "F.Fab")
			(effects
				(font
					(size 1.27 1.27)
				)
			)
		)
		(duplicate_pad_numbers_are_jumpers no)
		(fp_line
			(start -0.7874 0.4064)
			(end -0.7874 -0.4064)
			(stroke
				(width 0.1524)
				(type default)
			)
			(layer "F.SilkS")
		)
		(fp_line
			(start 0.7874 0.4064)
			(end -0.7874 0.4064)
			(stroke
				(width 0.1524)
				(type default)
			)
			(layer "F.SilkS")
		)
		(fp_line
			(start -0.7874 -0.4064)
			(end 0.7874 -0.4064)
			(stroke
				(width 0.1524)
				(type default)
			)
			(layer "F.SilkS")
		)
		(fp_line
			(start 0.7874 -0.4064)
			(end 0.7874 0.4064)
			(stroke
				(width 0.1524)
				(type default)
			)
			(layer "F.SilkS")
		)
		(fp_line
			(start -0.67945 0.3048)
			(end -0.67945 -0.305054)
			(stroke
				(width 0.1)
				(type default)
			)
			(layer "F.Fab")
		)
		(fp_line
			(start -0.12065 0.3048)
			(end -0.67945 0.3048)
			(stroke
				(width 0.1)
				(type default)
			)
			(layer "F.Fab")
		)
		(fp_line
			(start 0.120396 0.3048)
			(end 0.120396 0.2794)
			(stroke
				(width 0.1)
				(type default)
			)
			(layer "F.Fab")
		)
		(fp_line
			(start 0.67945 0.3048)
			(end 0.120396 0.3048)
			(stroke
				(width 0.1)
				(type default)
			)
			(layer "F.Fab")
		)
		(fp_line
			(start -0.12065 0.2794)
			(end -0.12065 0.3048)
			(stroke
				(width 0.1)
				(type default)
			)
			(layer "F.Fab")
		)
		(fp_line
			(start 0.120396 0.2794)
			(end -0.12065 0.2794)
			(stroke
				(width 0.1)
				(type default)
			)
			(layer "F.Fab")
		)
		(fp_line
			(start -0.12065 -0.2794)
			(end 0.12065 -0.2794)
			(stroke
				(width 0.1)
				(type default)
			)
			(layer "F.Fab")
		)
		(fp_line
			(start 0.12065 -0.2794)
			(end 0.12065 -0.3048)
			(stroke
				(width 0.1)
				(type default)
			)
			(layer "F.Fab")
		)
		(fp_line
			(start 0.12065 -0.3048)
			(end 0.67945 -0.3048)
			(stroke
				(width 0.1)
				(type default)
			)
			(layer "F.Fab")
		)
		(fp_line
			(start 0.67945 -0.3048)
			(end 0.67945 0.3048)
			(stroke
				(width 0.1)
				(type default)
			)
			(layer "F.Fab")
		)
		(fp_line
			(start -0.67945 -0.305054)
			(end -0.12065 -0.305054)
			(stroke
				(width 0.1)
				(type default)
			)
			(layer "F.Fab")
		)
		(fp_line
			(start -0.12065 -0.305054)
			(end -0.12065 -0.2794)
			(stroke
				(width 0.1)
				(type default)
			)
			(layer "F.Fab")
		)
		(pad "1" smd circle
			(at -0.40005 0 270)
			(size 0 0)
			(layers "F.Cu" "F.Mask" "F.Paste")
			(net "LED_RST_PLTRST_N")
		)
		(pad "2" smd circle
			(at 0.40005 0 270)
			(size 0 0)
			(layers "F.Cu" "F.Mask" "F.Paste")
			(net "P3V3_AUX")
		)
	)
	(footprint ""
		(layer "F.Cu")
		(at 364.50143 -260.364986 -90)
		(property "Reference" "C407"
			(at 0 0 270)
			(layer "F.SilkS")
			(hide yes)
			(effects
				(font
					(size 1.27 1.27)
				)
			)
		)
		(property "Value" ""
			(at 0 0 270)
			(layer "F.Fab")
			(effects
				(font
					(size 1.27 1.27)
				)
			)
		)
		(duplicate_pad_numbers_are_jumpers no)
		(fp_line
			(start -0.7874 0.4064)
			(end -0.7874 -0.4064)
			(stroke
				(width 0.1524)
				(type default)
			)
			(layer "F.SilkS")
		)
		(fp_line
			(start 0.7874 0.4064)
			(end -0.7874 0.4064)
			(stroke
				(width 0.1524)
				(type default)
			)
			(layer "F.SilkS")
		)
		(fp_line
			(start -0.7874 -0.4064)
			(end 0.7874 -0.4064)
			(stroke
				(width 0.1524)
				(type default)
			)
			(layer "F.SilkS")
		)
		(fp_line
			(start 0.7874 -0.4064)
			(end 0.7874 0.4064)
			(stroke
				(width 0.1524)
				(type default)
			)
			(layer "F.SilkS")
		)
		(fp_line
			(start -0.67945 0.3048)
			(end -0.67945 -0.305054)
			(stroke
				(width 0.1)
				(type default)
			)
			(layer "F.Fab")
		)
		(fp_line
			(start -0.12065 0.3048)
			(end -0.67945 0.3048)
			(stroke
				(width 0.1)
				(type default)
			)
			(layer "F.Fab")
		)
		(fp_line
			(start 0.120396 0.3048)
			(end 0.120396 0.2794)
			(stroke
				(width 0.1)
				(type default)
			)
			(layer "F.Fab")
		)
		(fp_line
			(start 0.67945 0.3048)
			(end 0.120396 0.3048)
			(stroke
				(width 0.1)
				(type default)
			)
			(layer "F.Fab")
		)
		(fp_line
			(start -0.12065 0.2794)
			(end -0.12065 0.3048)
			(stroke
				(width 0.1)
				(type default)
			)
			(layer "F.Fab")
		)
		(fp_line
			(start 0.120396 0.2794)
			(end -0.12065 0.2794)
			(stroke
				(width 0.1)
				(type default)
			)
			(layer "F.Fab")
		)
		(fp_line
			(start -0.12065 -0.2794)
			(end 0.12065 -0.2794)
			(stroke
				(width 0.1)
				(type default)
			)
			(layer "F.Fab")
		)
		(fp_line
			(start 0.12065 -0.2794)
			(end 0.12065 -0.3048)
			(stroke
				(width 0.1)
				(type default)
			)
			(layer "F.Fab")
		)
		(fp_line
			(start 0.12065 -0.3048)
			(end 0.67945 -0.3048)
			(stroke
				(width 0.1)
				(type default)
			)
			(layer "F.Fab")
		)
		(fp_line
			(start 0.67945 -0.3048)
			(end 0.67945 0.3048)
			(stroke
				(width 0.1)
				(type default)
			)
			(layer "F.Fab")
		)
		(fp_line
			(start -0.67945 -0.305054)
			(end -0.12065 -0.305054)
			(stroke
				(width 0.1)
				(type default)
			)
			(layer "F.Fab")
		)
		(fp_line
			(start -0.12065 -0.305054)
			(end -0.12065 -0.2794)
			(stroke
				(width 0.1)
				(type default)
			)
			(layer "F.Fab")
		)
		(pad "1" smd circle
			(at -0.40005 0 270)
			(size 0 0)
			(layers "F.Cu" "F.Mask" "F.Paste")
			(net "PVCCFA_EHV_FIVRA_CPU0")
		)
		(pad "2" smd circle
			(at 0.40005 0 270)
			(size 0 0)
			(layers "F.Cu" "F.Mask" "F.Paste")
			(net "GND")
		)
	)
	(footprint ""
		(layer "F.Cu")
		(at 206.45374 -131.669028 90)
		(property "Reference" "R2530"
			(at 0 0 90)
			(layer "F.SilkS")
			(hide yes)
			(effects
				(font
					(size 1.27 1.27)
				)
			)
		)
		(property "Value" ""
			(at 0 0 90)
			(layer "F.Fab")
			(effects
				(font
					(size 1.27 1.27)
				)
			)
		)
		(duplicate_pad_numbers_are_jumpers no)
		(fp_line
			(start 0.7874 -0.4064)
			(end 0.7874 0.4064)
			(stroke
				(width 0.1524)
				(type default)
			)
			(layer "F.SilkS")
		)
		(fp_line
			(start -0.7874 -0.4064)
			(end 0.7874 -0.4064)
			(stroke
				(width 0.1524)
				(type default)
			)
			(layer "F.SilkS")
		)
		(fp_line
			(start 0.7874 0.4064)
			(end -0.7874 0.4064)
			(stroke
				(width 0.1524)
				(type default)
			)
			(layer "F.SilkS")
		)
		(fp_line
			(start -0.7874 0.4064)
			(end -0.7874 -0.4064)
			(stroke
				(width 0.1524)
				(type default)
			)
			(layer "F.SilkS")
		)
		(fp_line
			(start -0.12065 -0.305054)
			(end -0.12065 -0.2794)
			(stroke
				(width 0.1)
				(type default)
			)
			(layer "F.Fab")
		)
		(fp_line
			(start -0.67945 -0.305054)
			(end -0.12065 -0.305054)
			(stroke
				(width 0.1)
				(type default)
			)
			(layer "F.Fab")
		)
		(fp_line
			(start 0.67945 -0.3048)
			(end 0.67945 0.3048)
			(stroke
				(width 0.1)
				(type default)
			)
			(layer "F.Fab")
		)
		(fp_line
			(start 0.12065 -0.3048)
			(end 0.67945 -0.3048)
			(stroke
				(width 0.1)
				(type default)
			)
			(layer "F.Fab")
		)
		(fp_line
			(start 0.12065 -0.2794)
			(end 0.12065 -0.3048)
			(stroke
				(width 0.1)
				(type default)
			)
			(layer "F.Fab")
		)
		(fp_line
			(start -0.12065 -0.2794)
			(end 0.12065 -0.2794)
			(stroke
				(width 0.1)
				(type default)
			)
			(layer "F.Fab")
		)
		(fp_line
			(start 0.120396 0.2794)
			(end -0.12065 0.2794)
			(stroke
				(width 0.1)
				(type default)
			)
			(layer "F.Fab")
		)
		(fp_line
			(start -0.12065 0.2794)
			(end -0.12065 0.3048)
			(stroke
				(width 0.1)
				(type default)
			)
			(layer "F.Fab")
		)
		(fp_line
			(start 0.67945 0.3048)
			(end 0.120396 0.3048)
			(stroke
				(width 0.1)
				(type default)
			)
			(layer "F.Fab")
		)
		(fp_line
			(start 0.120396 0.3048)
			(end 0.120396 0.2794)
			(stroke
				(width 0.1)
				(type default)
			)
			(layer "F.Fab")
		)
		(fp_line
			(start -0.12065 0.3048)
			(end -0.67945 0.3048)
			(stroke
				(width 0.1)
				(type default)
			)
			(layer "F.Fab")
		)
		(fp_line
			(start -0.67945 0.3048)
			(end -0.67945 -0.305054)
			(stroke
				(width 0.1)
				(type default)
			)
			(layer "F.Fab")
		)
		(pad "1" smd circle
			(at -0.40005 0 90)
			(size 0 0)
			(layers "F.Cu" "F.Mask" "F.Paste")
			(net "P12V_AUX")
		)
		(pad "2" smd circle
			(at 0.40005 0 90)
			(size 0 0)
			(layers "F.Cu" "F.Mask" "F.Paste")
			(net "P12V_AUX_BLEEDING")
		)
	)
)
